FILE_TYPE=LIBRARY_PARTS;
primitive 'FSA3357K8X';
  pin
    'A':
      PIN_NUMBER='(7)';
      BIDIRECTIONAL='TRUE';
      INPUT_LOAD='(-0.01,0.01)';
      OUTPUT_LOAD='(1.0,-1.0)';
    'GND':
      PIN_NUMBER='(4)';
      PINUSE='POWER';
      NO_LOAD_CHECK='Both';
      NO_IO_CHECK='Both';
      NO_ASSERT_CHECK='TRUE';
      NO_DIR_CHECK='TRUE';
      ALLOW_CONNECT='TRUE';
    'B2':
      PIN_NUMBER='(3)';
      BIDIRECTIONAL='TRUE';
      INPUT_LOAD='(-0.01,0.01)';
      OUTPUT_LOAD='(1.0,-1.0)';
    'S2':
      PIN_NUMBER='(5)';
      INPUT_LOAD='(-0.01,0.01)';
    'VCC':
      PIN_NUMBER='(8)';
      PINUSE='POWER';
      NO_LOAD_CHECK='Both';
      NO_IO_CHECK='Both';
      NO_ASSERT_CHECK='TRUE';
      NO_DIR_CHECK='TRUE';
      ALLOW_CONNECT='TRUE';
    'B1':
      PIN_NUMBER='(2)';
      BIDIRECTIONAL='TRUE';
      INPUT_LOAD='(-0.01,0.01)';
      OUTPUT_LOAD='(1.0,-1.0)';
    'B0':
      PIN_NUMBER='(1)';
      BIDIRECTIONAL='TRUE';
      INPUT_LOAD='(-0.01,0.01)';
      OUTPUT_LOAD='(1.0,-1.0)';
    'S1':
      PIN_NUMBER='(6)';
      INPUT_LOAD='(-0.01,0.01)';
  end_pin;
  body
    PART_NAME='FSA3357K8X';
    BODY_NAME='FSA3357K8X';
    PHYS_DES_PREFIX='U';
    CLASS='IC';
  end_body;
end_primitive;

END.
